(kicad_pcb
	(version 20260206)
	(generator "pcbnew")
	(generator_version "10.0")
	(general
		(thickness 1.6)
		(legacy_teardrops no)
	)
	(paper "A4")
	(title_block
		(title "Bryce Canyon_F.DPB_16315-1-OCP.brd")
		(comment 1 "Bryce Canyon / footprints 1951-1957 of 2223")
	)
	(layers
		(0 "F.Cu" signal "TOP")
		(4 "In1.Cu" signal "L2GND")
		(6 "In2.Cu" signal "L3")
		(8 "In3.Cu" signal "L4GND")
		(10 "In4.Cu" signal "L5")
		(12 "In5.Cu" signal "L6VCC")
		(14 "In6.Cu" signal "L7VCC")
		(16 "In7.Cu" signal "L8")
		(18 "In8.Cu" signal "L9GND")
		(20 "In9.Cu" signal "L10")
		(22 "In10.Cu" signal "L11GND")
		(2 "B.Cu" signal "BOTTOM")
		(9 "F.Adhes" user "F.Adhesive")
		(11 "B.Adhes" user "B.Adhesive")
		(13 "F.Paste" user "Package Geometry/Pastemask Top")
		(15 "B.Paste" user "Package Geometry/Pastemask Bottom")
		(5 "F.SilkS" user "Ref Des/Silkscreen Top")
		(7 "B.SilkS" user "Ref Des/Silkscreen Bottom")
		(1 "F.Mask" user "Board Geometry/Soldermask Top")
		(3 "B.Mask" user "Board Geometry/Soldermask Bottom")
		(17 "Dwgs.User" user "User.Drawings")
		(19 "Cmts.User" user "User.Comments")
		(21 "Eco1.User" user "User.Eco1")
		(23 "Eco2.User" user "User.Eco2")
		(25 "Edge.Cuts" user "Board Geometry/Outline")
		(27 "Margin" user)
		(31 "F.CrtYd" user "Package Geometry/Place Bound Top")
		(29 "B.CrtYd" user "Package Geometry/Place Bound Bottom")
		(35 "F.Fab" user "Ref Des/Assembly Top")
		(33 "B.Fab" user "Ref Des/Assembly Bottom")
	)
	(footprint ""
		(layer "F.Cu")
		(at 64.0588 -47.749968 -90)
		(property "Reference" "VIA60"
			(at 0 0 270)
			(layer "F.SilkS")
			(hide yes)
			(effects
				(font
					(size 1.27 1.27)
				)
			)
		)
		(property "Value" "100OHM-8L-1D6MM-L18L16-GP"
			(at -3.7211 -4.5085 270)
			(unlocked yes)
			(layer "F.Fab")
			(hide yes)
			(effects
				(font
					(size 1.016 1.016)
					(thickness 0.1524)
				)
			)
		)
		(property "Device Type" "VIA-PCIE-4P-394076"
			(at -3.7211 -6.0325 270)
			(unlocked yes)
			(layer "F.Fab")
			(hide yes)
			(effects
				(font
					(size 1.016 1.016)
					(thickness 0.1524)
				)
			)
		)
		(duplicate_pad_numbers_are_jumpers no)
		(fp_rect
			(start -1.9685 0.381)
			(end 1.9685 -0.381)
			(stroke
				(width 0)
				(type default)
			)
			(fill no)
			(layer "F.CrtYd")
		)
		(fp_rect
			(start -1.9685 0.381)
			(end 1.9685 -0.381)
			(stroke
				(width 0)
				(type default)
			)
			(fill no)
			(layer "F.Fab")
		)
		(pad "1" thru_hole circle
			(at -1.5875 0 270)
			(size 0.508 0.508)
			(drill 0.254)
			(layers "*.Cu" "*.Mask")
			(remove_unused_layers no)
			(net "GND")
			(clearance 0.127)
			(thermal_gap 0.127)
		)
		(pad "2" thru_hole circle
			(at -0.5715 0 270)
			(size 0.508 0.508)
			(drill 0.254)
			(layers "*.Cu" "*.Mask")
			(remove_unused_layers no)
			(net "PHY_DRV_A_TO_SCC_A_25_DP")
			(clearance 0.127)
			(thermal_gap 0.127)
		)
		(pad "3" thru_hole circle
			(at 0.5715 0 270)
			(size 0.508 0.508)
			(drill 0.254)
			(layers "*.Cu" "*.Mask")
			(remove_unused_layers no)
			(net "PHY_DRV_A_TO_SCC_A_25_DN")
			(clearance 0.127)
			(thermal_gap 0.127)
		)
		(pad "4" thru_hole circle
			(at 1.5875 0 270)
			(size 0.508 0.508)
			(drill 0.254)
			(layers "*.Cu" "*.Mask")
			(remove_unused_layers no)
			(net "GND")
			(clearance 0.127)
			(thermal_gap 0.127)
		)
	)
	(footprint ""
		(layer "F.Cu")
		(at 364.7948 -140.1064 180)
		(property "Reference" "C570"
			(at 0 0 180)
			(layer "F.SilkS")
			(hide yes)
			(effects
				(font
					(size 1.27 1.27)
				)
			)
		)
		(property "Value" "SCD015U25V2KX-GP"
			(at 1.1811 -2.7051 180)
			(unlocked yes)
			(layer "F.Fab")
			(hide yes)
			(effects
				(font
					(size 1.016 1.016)
					(thickness 0.1524)
				)
			)
		)
		(property "Device Type" "C402H22"
			(at 1.1811 -4.2291 180)
			(unlocked yes)
			(layer "F.Fab")
			(hide yes)
			(effects
				(font
					(size 1.016 1.016)
					(thickness 0.1524)
				)
			)
		)
		(duplicate_pad_numbers_are_jumpers no)
		(fp_rect
			(start -0.4318 0.9525)
			(end 0.4318 -0.9525)
			(stroke
				(width 0)
				(type default)
			)
			(fill no)
			(layer "F.CrtYd")
		)
		(fp_rect
			(start -0.4318 0.9525)
			(end 0.4318 -0.9525)
			(stroke
				(width 0)
				(type default)
			)
			(fill no)
			(layer "F.Fab")
		)
		(pad "1" smd custom
			(at 0 -0.4445 180)
			(size 0.1524 0.1524)
			(layers "F.Cu" "F.Mask" "F.Paste")
			(net "MB1_HS_SENSE_P")
			(options
				(clearance outline)
				(anchor circle)
			)
			(primitives
				(gr_poly
					(pts
						(arc
							(start 0.3048 -0.2032)
							(mid 0.275042 -0.275042)
							(end 0.2032 -0.3048)
						)
						(arc
							(start -0.2032 -0.3048)
							(mid -0.275042 -0.275042)
							(end -0.3048 -0.2032)
						)
						(arc
							(start -0.3048 0.2032)
							(mid -0.275042 0.275042)
							(end -0.2032 0.3048)
						)
						(arc
							(start 0.2032 0.3048)
							(mid 0.275042 0.275042)
							(end 0.3048 0.2032)
						)
					)
					(width 0)
					(fill yes)
				)
			)
		)
		(pad "2" smd custom
			(at 0 0.4445 180)
			(size 0.1524 0.1524)
			(layers "F.Cu" "F.Mask" "F.Paste")
			(net "MB1_HS_SENSE_N")
			(options
				(clearance outline)
				(anchor circle)
			)
			(primitives
				(gr_poly
					(pts
						(arc
							(start 0.3048 -0.2032)
							(mid 0.275042 -0.275042)
							(end 0.2032 -0.3048)
						)
						(arc
							(start -0.2032 -0.3048)
							(mid -0.275042 -0.275042)
							(end -0.3048 -0.2032)
						)
						(arc
							(start -0.3048 0.2032)
							(mid -0.275042 0.275042)
							(end -0.2032 0.3048)
						)
						(arc
							(start 0.2032 0.3048)
							(mid 0.275042 0.275042)
							(end 0.3048 0.2032)
						)
					)
					(width 0)
					(fill yes)
				)
			)
		)
	)
	(footprint ""
		(layer "F.Cu")
		(at 32.528002 -253.29515 -90)
		(property "Reference" "C603"
			(at 0 0 270)
			(layer "F.SilkS")
			(hide yes)
			(effects
				(font
					(size 1.27 1.27)
				)
			)
		)
		(property "Value" "SC1U16V3KX-5GP"
			(at 0 -2.8194 270)
			(unlocked yes)
			(layer "F.Fab")
			(hide yes)
			(effects
				(font
					(size 1.016 1.016)
					(thickness 0.1524)
				)
			)
		)
		(property "Device Type" "C603H36"
			(at 0 -4.3434 270)
			(unlocked yes)
			(layer "F.Fab")
			(hide yes)
			(effects
				(font
					(size 1.016 1.016)
					(thickness 0.1524)
				)
			)
		)
		(duplicate_pad_numbers_are_jumpers no)
		(fp_line
			(start 0.508 0)
			(end -0.508 0)
			(stroke
				(width 0.2032)
				(type default)
			)
			(layer "F.SilkS")
		)
		(fp_rect
			(start -0.5842 1.3335)
			(end 0.5842 -1.3335)
			(stroke
				(width 0)
				(type default)
			)
			(fill no)
			(layer "F.CrtYd")
		)
		(fp_rect
			(start -0.5842 1.3335)
			(end 0.5842 -1.3335)
			(stroke
				(width 0)
				(type default)
			)
			(fill no)
			(layer "F.Fab")
		)
		(pad "1" smd custom
			(at 0 -0.762 270)
			(size 0.2159 0.2159)
			(layers "F.Cu" "F.Mask" "F.Paste")
			(net "P5V_A_EN_R")
			(options
				(clearance outline)
				(anchor circle)
			)
			(primitives
				(gr_poly
					(pts
						(arc
							(start -0.3302 -0.4318)
							(mid -0.402042 -0.402042)
							(end -0.4318 -0.3302)
						)
						(arc
							(start -0.4318 0.3302)
							(mid -0.402042 0.402042)
							(end -0.3302 0.4318)
						)
						(arc
							(start 0.3302 0.4318)
							(mid 0.402042 0.402042)
							(end 0.4318 0.3302)
						)
						(arc
							(start 0.4318 -0.3302)
							(mid 0.402042 -0.402042)
							(end 0.3302 -0.4318)
						)
					)
					(width 0)
					(fill yes)
				)
			)
		)
		(pad "2" smd custom
			(at 0 0.762 270)
			(size 0.2159 0.2159)
			(layers "F.Cu" "F.Mask" "F.Paste")
			(net "GND")
			(options
				(clearance outline)
				(anchor circle)
			)
			(primitives
				(gr_poly
					(pts
						(arc
							(start -0.3302 -0.4318)
							(mid -0.402042 -0.402042)
							(end -0.4318 -0.3302)
						)
						(arc
							(start -0.4318 0.3302)
							(mid -0.402042 0.402042)
							(end -0.3302 0.4318)
						)
						(arc
							(start 0.3302 0.4318)
							(mid 0.402042 0.402042)
							(end 0.4318 0.3302)
						)
						(arc
							(start 0.4318 -0.3302)
							(mid 0.402042 -0.402042)
							(end 0.3302 -0.4318)
						)
					)
					(width 0)
					(fill yes)
				)
			)
		)
	)
	(footprint ""
		(layer "F.Cu")
		(at 369.935506 -132.096764)
		(property "Reference" "R1095"
			(at 0 0 0)
			(layer "F.SilkS")
			(hide yes)
			(effects
				(font
					(size 1.27 1.27)
				)
			)
		)
		(property "Value" "22D6R2F-L1-GP"
			(at 0.064008 -3.993896 0)
			(unlocked yes)
			(layer "F.Fab")
			(hide yes)
			(effects
				(font
					(size 1.016 1.016)
					(thickness 0.1524)
				)
			)
		)
		(property "Device Type" "R402H16"
			(at 0.064008 -5.517896 0)
			(unlocked yes)
			(layer "F.Fab")
			(hide yes)
			(effects
				(font
					(size 1.016 1.016)
					(thickness 0.1524)
				)
			)
		)
		(duplicate_pad_numbers_are_jumpers no)
		(fp_line
			(start -0.508 -0.9398)
			(end -0.508 0.9398)
			(stroke
				(width 0.1524)
				(type default)
			)
			(layer "F.SilkS")
		)
		(fp_line
			(start 0.508 -0.9398)
			(end -0.508 -0.9398)
			(stroke
				(width 0.1524)
				(type default)
			)
			(layer "F.SilkS")
		)
		(fp_rect
			(start -0.508 0.9398)
			(end 0.508 -0.9398)
			(stroke
				(width 0)
				(type default)
			)
			(fill no)
			(layer "F.CrtYd")
		)
		(fp_rect
			(start -0.508 0.9398)
			(end 0.508 -0.9398)
			(stroke
				(width 0)
				(type default)
			)
			(fill no)
			(layer "F.Fab")
		)
		(pad "1" smd custom
			(at 0 -0.4445)
			(size 0.1397 0.1397)
			(layers "F.Cu" "F.Mask" "F.Paste")
			(net "MB1_ISTART_R")
			(options
				(clearance outline)
				(anchor circle)
			)
			(primitives
				(gr_poly
					(pts
						(arc
							(start -0.1778 -0.2794)
							(mid -0.249642 -0.249642)
							(end -0.2794 -0.1778)
						)
						(arc
							(start -0.2794 0.1778)
							(mid -0.249642 0.249642)
							(end -0.1778 0.2794)
						)
						(arc
							(start 0.1778 0.2794)
							(mid 0.249642 0.249642)
							(end 0.2794 0.1778)
						)
						(arc
							(start 0.2794 -0.1778)
							(mid 0.249642 -0.249642)
							(end 0.1778 -0.2794)
						)
					)
					(width 0)
					(fill yes)
				)
			)
		)
		(pad "2" smd custom
			(at 0 0.4445)
			(size 0.1397 0.1397)
			(layers "F.Cu" "F.Mask" "F.Paste")
			(net "AGND_CURRENT_MONOB")
			(options
				(clearance outline)
				(anchor circle)
			)
			(primitives
				(gr_poly
					(pts
						(arc
							(start -0.1778 -0.2794)
							(mid -0.249642 -0.249642)
							(end -0.2794 -0.1778)
						)
						(arc
							(start -0.2794 0.1778)
							(mid -0.249642 0.249642)
							(end -0.1778 0.2794)
						)
						(arc
							(start 0.1778 0.2794)
							(mid 0.249642 0.249642)
							(end 0.2794 0.1778)
						)
						(arc
							(start 0.2794 -0.1778)
							(mid 0.249642 -0.249642)
							(end 0.1778 -0.2794)
						)
					)
					(width 0)
					(fill yes)
				)
			)
		)
	)
	(footprint ""
		(layer "F.Cu")
		(at 156.275532 -136.84123 90)
		(property "Reference" "R1053"
			(at 0 0 90)
			(layer "F.SilkS")
			(hide yes)
			(effects
				(font
					(size 1.27 1.27)
				)
			)
		)
		(property "Value" "10R2F-L-GP"
			(at 0.064008 -3.993896 90)
			(unlocked yes)
			(layer "F.Fab")
			(hide yes)
			(effects
				(font
					(size 1.016 1.016)
					(thickness 0.1524)
				)
			)
		)
		(property "Device Type" "R402H14"
			(at 0.064008 -5.517896 90)
			(unlocked yes)
			(layer "F.Fab")
			(hide yes)
			(effects
				(font
					(size 1.016 1.016)
					(thickness 0.1524)
				)
			)
		)
		(duplicate_pad_numbers_are_jumpers no)
		(fp_line
			(start 0.508 -0.9398)
			(end -0.508 -0.9398)
			(stroke
				(width 0.1524)
				(type default)
			)
			(layer "F.SilkS")
		)
		(fp_line
			(start -0.508 -0.9398)
			(end -0.508 0.9398)
			(stroke
				(width 0.1524)
				(type default)
			)
			(layer "F.SilkS")
		)
		(fp_rect
			(start -0.508 0.9398)
			(end 0.508 -0.9398)
			(stroke
				(width 0)
				(type default)
			)
			(fill no)
			(layer "F.CrtYd")
		)
		(fp_rect
			(start -0.508 0.9398)
			(end 0.508 -0.9398)
			(stroke
				(width 0)
				(type default)
			)
			(fill no)
			(layer "F.Fab")
		)
		(pad "1" smd custom
			(at 0 -0.4445 90)
			(size 0.1397 0.1397)
			(layers "F.Cu" "F.Mask" "F.Paste")
			(net "MB0_CM_SENSE_R1_N")
			(options
				(clearance outline)
				(anchor circle)
			)
			(primitives
				(gr_poly
					(pts
						(arc
							(start -0.1778 -0.2794)
							(mid -0.249642 -0.249642)
							(end -0.2794 -0.1778)
						)
						(arc
							(start -0.2794 0.1778)
							(mid -0.249642 0.249642)
							(end -0.1778 0.2794)
						)
						(arc
							(start 0.1778 0.2794)
							(mid 0.249642 0.249642)
							(end 0.2794 0.1778)
						)
						(arc
							(start 0.2794 -0.1778)
							(mid 0.249642 -0.249642)
							(end 0.1778 -0.2794)
						)
					)
					(width 0)
					(fill yes)
				)
			)
		)
		(pad "2" smd custom
			(at 0 0.4445 90)
			(size 0.1397 0.1397)
			(layers "F.Cu" "F.Mask" "F.Paste")
			(net "MB0_CM_SENSE_N")
			(options
				(clearance outline)
				(anchor circle)
			)
			(primitives
				(gr_poly
					(pts
						(arc
							(start -0.1778 -0.2794)
							(mid -0.249642 -0.249642)
							(end -0.2794 -0.1778)
						)
						(arc
							(start -0.2794 0.1778)
							(mid -0.249642 0.249642)
							(end -0.1778 0.2794)
						)
						(arc
							(start 0.1778 0.2794)
							(mid 0.249642 0.249642)
							(end 0.2794 0.1778)
						)
						(arc
							(start 0.2794 -0.1778)
							(mid 0.249642 -0.249642)
							(end 0.1778 -0.2794)
						)
					)
					(width 0)
					(fill yes)
				)
			)
		)
	)
	(footprint ""
		(layer "F.Cu")
		(at 338.074 -164.443918 90)
		(property "Reference" "R560"
			(at 0 0 90)
			(layer "F.SilkS")
			(hide yes)
			(effects
				(font
					(size 1.27 1.27)
				)
			)
		)
		(property "Value" "200KR2F-L-GP"
			(at 0.064008 -3.993896 90)
			(unlocked yes)
			(layer "F.Fab")
			(hide yes)
			(effects
				(font
					(size 1.016 1.016)
					(thickness 0.1524)
				)
			)
		)
		(property "Device Type" "R402H16"
			(at 0.064008 -5.517896 90)
			(unlocked yes)
			(layer "F.Fab")
			(hide yes)
			(effects
				(font
					(size 1.016 1.016)
					(thickness 0.1524)
				)
			)
		)
		(duplicate_pad_numbers_are_jumpers no)
		(fp_line
			(start 0.508 -0.9398)
			(end -0.508 -0.9398)
			(stroke
				(width 0.1524)
				(type default)
			)
			(layer "F.SilkS")
		)
		(fp_line
			(start -0.508 -0.9398)
			(end -0.508 0.9398)
			(stroke
				(width 0.1524)
				(type default)
			)
			(layer "F.SilkS")
		)
		(fp_rect
			(start -0.508 0.9398)
			(end 0.508 -0.9398)
			(stroke
				(width 0)
				(type default)
			)
			(fill no)
			(layer "F.CrtYd")
		)
		(fp_rect
			(start -0.508 0.9398)
			(end 0.508 -0.9398)
			(stroke
				(width 0)
				(type default)
			)
			(fill no)
			(layer "F.Fab")
		)
		(pad "1" smd custom
			(at 0 -0.4445 90)
			(size 0.1397 0.1397)
			(layers "F.Cu" "F.Mask" "F.Paste")
			(net "SW_HDD_R18")
			(options
				(clearance outline)
				(anchor circle)
			)
			(primitives
				(gr_poly
					(pts
						(arc
							(start -0.1778 -0.2794)
							(mid -0.249642 -0.249642)
							(end -0.2794 -0.1778)
						)
						(arc
							(start -0.2794 0.1778)
							(mid -0.249642 0.249642)
							(end -0.1778 0.2794)
						)
						(arc
							(start 0.1778 0.2794)
							(mid 0.249642 0.249642)
							(end 0.2794 0.1778)
						)
						(arc
							(start 0.2794 -0.1778)
							(mid 0.249642 -0.249642)
							(end 0.1778 -0.2794)
						)
					)
					(width 0)
					(fill yes)
				)
			)
		)
		(pad "2" smd custom
			(at 0 0.4445 90)
			(size 0.1397 0.1397)
			(layers "F.Cu" "F.Mask" "F.Paste")
			(net "SW_HDD_N18")
			(options
				(clearance outline)
				(anchor circle)
			)
			(primitives
				(gr_poly
					(pts
						(arc
							(start -0.1778 -0.2794)
							(mid -0.249642 -0.249642)
							(end -0.2794 -0.1778)
						)
						(arc
							(start -0.2794 0.1778)
							(mid -0.249642 0.249642)
							(end -0.1778 0.2794)
						)
						(arc
							(start 0.1778 0.2794)
							(mid 0.249642 0.249642)
							(end 0.2794 0.1778)
						)
						(arc
							(start 0.2794 -0.1778)
							(mid 0.249642 -0.249642)
							(end 0.1778 -0.2794)
						)
					)
					(width 0)
					(fill yes)
				)
			)
		)
	)
	(footprint ""
		(layer "F.Cu")
		(at 272.923 -284.734 180)
		(property "Reference" "R115"
			(at 0 0 180)
			(layer "F.SilkS")
			(hide yes)
			(effects
				(font
					(size 1.27 1.27)
				)
			)
		)
		(property "Value" "0R2J-2-GP"
			(at 0.064008 -3.993896 180)
			(unlocked yes)
			(layer "F.Fab")
			(hide yes)
			(effects
				(font
					(size 1.016 1.016)
					(thickness 0.1524)
				)
			)
		)
		(property "Device Type" "R402H16"
			(at 0.064008 -5.517896 180)
			(unlocked yes)
			(layer "F.Fab")
			(hide yes)
			(effects
				(font
					(size 1.016 1.016)
					(thickness 0.1524)
				)
			)
		)
		(duplicate_pad_numbers_are_jumpers no)
		(fp_line
			(start 0.508 -0.9398)
			(end -0.508 -0.9398)
			(stroke
				(width 0.1524)
				(type default)
			)
			(layer "F.SilkS")
		)
		(fp_line
			(start -0.508 -0.9398)
			(end -0.508 0.9398)
			(stroke
				(width 0.1524)
				(type default)
			)
			(layer "F.SilkS")
		)
		(fp_rect
			(start -0.508 0.9398)
			(end 0.508 -0.9398)
			(stroke
				(width 0)
				(type default)
			)
			(fill no)
			(layer "F.CrtYd")
		)
		(fp_rect
			(start -0.508 0.9398)
			(end 0.508 -0.9398)
			(stroke
				(width 0)
				(type default)
			)
			(fill no)
			(layer "F.Fab")
		)
		(pad "1" smd custom
			(at 0 -0.4445 180)
			(size 0.1397 0.1397)
			(layers "F.Cu" "F.Mask" "F.Paste")
			(net "IO_EXP1_LED_SDA")
			(options
				(clearance outline)
				(anchor circle)
			)
			(primitives
				(gr_poly
					(pts
						(arc
							(start -0.1778 -0.2794)
							(mid -0.249642 -0.249642)
							(end -0.2794 -0.1778)
						)
						(arc
							(start -0.2794 0.1778)
							(mid -0.249642 0.249642)
							(end -0.1778 0.2794)
						)
						(arc
							(start 0.1778 0.2794)
							(mid 0.249642 0.249642)
							(end 0.2794 0.1778)
						)
						(arc
							(start 0.2794 -0.1778)
							(mid 0.249642 -0.249642)
							(end 0.1778 -0.2794)
						)
					)
					(width 0)
					(fill yes)
				)
			)
		)
		(pad "2" smd custom
			(at 0 0.4445 180)
			(size 0.1397 0.1397)
			(layers "F.Cu" "F.Mask" "F.Paste")
			(net "I2C_DRIVE_A_FLT_LED_SDA")
			(options
				(clearance outline)
				(anchor circle)
			)
			(primitives
				(gr_poly
					(pts
						(arc
							(start -0.1778 -0.2794)
							(mid -0.249642 -0.249642)
							(end -0.2794 -0.1778)
						)
						(arc
							(start -0.2794 0.1778)
							(mid -0.249642 0.249642)
							(end -0.1778 0.2794)
						)
						(arc
							(start 0.1778 0.2794)
							(mid 0.249642 0.249642)
							(end 0.2794 0.1778)
						)
						(arc
							(start 0.2794 -0.1778)
							(mid 0.249642 -0.249642)
							(end 0.1778 -0.2794)
						)
					)
					(width 0)
					(fill yes)
				)
			)
		)
	)
)
